# BASEBOARD_FAB2 (Tioga Pass) — schematic netlist excerpt (pin names and nets, part order shuffled) for the footprints in the layout excerpt that follows; sources: Cadence DE-HDL packaged netlist, KiCad conversion of Wiwynn_Tioga_Pass_MB.brd

R1U33  649R2F-GP  1%  pkg RCL_GP  page 169 : \1\ = A_P12V_STBY_SCALED ; \2\ = GND
R25W97  RES  4.75K 1% EMPTY  pkg 0402  page 150 : A = P3V3_STBY ; B = SPI_BMC_BT_DI
R9F22  RES  20.0 1% CHIP  pkg 0402  page 160 : A = SMB_LAN_STBY_LVC3_SCL_R ; B = SMB_LAN_STBY_LVC3_SCL

(kicad_pcb
	(version 20260206)
	(generator "pcbnew")
	(generator_version "10.0")
	(general
		(thickness 1.6)
		(legacy_teardrops no)
	)
	(paper "A4")
	(title_block
		(title "Wiwynn_Tioga_Pass_MB.brd")
		(comment 1 "Tioga Pass / footprints 4736-4738 of 4770")
	)
	(layers
		(0 "F.Cu" signal "TOP")
		(4 "In1.Cu" signal "L2GND")
		(6 "In2.Cu" signal "L3")
		(8 "In3.Cu" signal "L4GND")
		(10 "In4.Cu" signal "L5")
		(12 "In5.Cu" signal "L6GND")
		(14 "In6.Cu" signal "L7VCC")
		(16 "In7.Cu" signal "L8VCC")
		(18 "In8.Cu" signal "L9GND")
		(20 "In9.Cu" signal "L10")
		(22 "In10.Cu" signal "L11GND")
		(24 "In11.Cu" signal "L12")
		(26 "In12.Cu" signal "L13GND")
		(2 "B.Cu" signal "BOTTOM")
		(9 "F.Adhes" user "F.Adhesive")
		(11 "B.Adhes" user "B.Adhesive")
		(13 "F.Paste" user "Package Geometry/Pastemask Top")
		(15 "B.Paste" user "Package Geometry/Pastemask Bottom")
		(5 "F.SilkS" user "Ref Des/Silkscreen Top")
		(7 "B.SilkS" user "Ref Des/Silkscreen Bottom")
		(1 "F.Mask" user "Board Geometry/Soldermask Top")
		(3 "B.Mask" user "Board Geometry/Soldermask Bottom")
		(17 "Dwgs.User" user "User.Drawings")
		(19 "Cmts.User" user "User.Comments")
		(21 "Eco1.User" user "User.Eco1")
		(23 "Eco2.User" user "User.Eco2")
		(25 "Edge.Cuts" user "Board Geometry/Outline")
		(27 "Margin" user)
		(31 "F.CrtYd" user "Package Geometry/Place Bound Top")
		(29 "B.CrtYd" user "Package Geometry/Place Bound Bottom")
		(35 "F.Fab" user "Ref Des/Assembly Top")
		(33 "B.Fab" user "Ref Des/Assembly Bottom")
	)
	(footprint ""
		(layer "B.Cu")
		(at 420.077646 -45.539152)
		(property "Reference" "R25W97"
			(at 0.8382 -0.67818 0)
			(unlocked yes)
			(layer "B.SilkS")
			(effects
				(font
					(size 0.4064 0.254)
					(thickness 0.1524)
				)
				(justify left mirror)
			)
		)
		(property "Value" ""
			(at 0 0 0)
			(layer "B.Fab")
			(effects
				(font
					(size 1.27 1.27)
				)
				(justify mirror)
			)
		)
		(duplicate_pad_numbers_are_jumpers no)
		(fp_poly
			(pts
				(xy 0.2794 -0.1016) (xy -0.2794 -0.1016) (xy -0.2794 0.9906) (xy 0.2794 0.9906)
			)
			(stroke
				(width 0)
				(type default)
			)
			(fill no)
			(layer "B.CrtYd")
		)
		(fp_line
			(start -0.2794 -0.1016)
			(end 0.2794 -0.1016)
			(stroke
				(width 0.1)
				(type default)
			)
			(layer "B.Fab")
		)
		(fp_line
			(start -0.2794 0.9906)
			(end -0.2794 -0.1016)
			(stroke
				(width 0.1)
				(type default)
			)
			(layer "B.Fab")
		)
		(fp_line
			(start 0.2794 -0.1016)
			(end 0.2794 0.9906)
			(stroke
				(width 0.1)
				(type default)
			)
			(layer "B.Fab")
		)
		(fp_line
			(start 0.2794 0.9906)
			(end -0.2794 0.9906)
			(stroke
				(width 0.1)
				(type default)
			)
			(layer "B.Fab")
		)
		(pad "1" smd rect
			(at 0 0 180)
			(size 0.508 0.508)
			(layers "B.Cu" "B.Mask" "B.Paste")
			(net "P3V3_STBY")
		)
		(pad "2" smd rect
			(at 0 0.889 180)
			(size 0.508 0.508)
			(layers "B.Cu" "B.Mask" "B.Paste")
			(net "SPI_BMC_BT_DI")
		)
		(zone
			(layer "B.Cu")
			(hatch none 0.5)
			(connect_pads
				(clearance 0)
			)
			(min_thickness 0.25)
			(keepout
				(tracks allowed)
				(vias not_allowed)
				(pads allowed)
				(copperpour not_allowed)
				(footprints allowed)
			)
			(placement
				(enabled no)
				(sheetname "")
			)
			(fill
				(thermal_gap 0.5)
				(thermal_bridge_width 0.5)
				(island_removal_mode 0)
			)
			(polygon
				(pts
					(xy 420.331646 -45.285152) (xy 419.823646 -45.285152) (xy 419.823646 -44.904152) (xy 420.331646 -44.904152)
				)
			)
		)
		(zone
			(layer "B.Cu")
			(hatch none 0.5)
			(connect_pads
				(clearance 0)
			)
			(min_thickness 0.25)
			(keepout
				(tracks not_allowed)
				(vias allowed)
				(pads allowed)
				(copperpour not_allowed)
				(footprints allowed)
			)
			(placement
				(enabled no)
				(sheetname "")
			)
			(fill
				(thermal_gap 0.5)
				(thermal_bridge_width 0.5)
				(island_removal_mode 0)
			)
			(polygon
				(pts
					(xy 420.331646 -44.904152) (xy 419.823646 -44.904152) (xy 419.823646 -45.285152) (xy 420.331646 -45.285152)
				)
			)
		)
	)
	(footprint ""
		(layer "B.Cu")
		(at 415.708846 -44.650152 180)
		(property "Reference" "R9F22"
			(at 0 0 0)
			(layer "B.SilkS")
			(hide yes)
			(effects
				(font
					(size 1.27 1.27)
				)
				(justify mirror)
			)
		)
		(property "Value" ""
			(at 0 0 0)
			(layer "B.Fab")
			(effects
				(font
					(size 1.27 1.27)
				)
				(justify mirror)
			)
		)
		(duplicate_pad_numbers_are_jumpers no)
		(fp_poly
			(pts
				(xy 0.2794 -0.1016) (xy -0.2794 -0.1016) (xy -0.2794 0.9906) (xy 0.2794 0.9906)
			)
			(stroke
				(width 0)
				(type default)
			)
			(fill no)
			(layer "B.CrtYd")
		)
		(fp_line
			(start 0.2794 0.9906)
			(end -0.2794 0.9906)
			(stroke
				(width 0.1)
				(type default)
			)
			(layer "B.Fab")
		)
		(fp_line
			(start 0.2794 -0.1016)
			(end 0.2794 0.9906)
			(stroke
				(width 0.1)
				(type default)
			)
			(layer "B.Fab")
		)
		(fp_line
			(start -0.2794 0.9906)
			(end -0.2794 -0.1016)
			(stroke
				(width 0.1)
				(type default)
			)
			(layer "B.Fab")
		)
		(fp_line
			(start -0.2794 -0.1016)
			(end 0.2794 -0.1016)
			(stroke
				(width 0.1)
				(type default)
			)
			(layer "B.Fab")
		)
		(pad "1" smd rect
			(at 0 0)
			(size 0.508 0.508)
			(layers "B.Cu" "B.Mask" "B.Paste")
			(net "SMB_LAN_STBY_LVC3_SCL_R")
		)
		(pad "2" smd rect
			(at 0 0.889)
			(size 0.508 0.508)
			(layers "B.Cu" "B.Mask" "B.Paste")
			(net "SMB_LAN_STBY_LVC3_SCL")
		)
		(zone
			(layer "B.Cu")
			(hatch none 0.5)
			(connect_pads
				(clearance 0)
			)
			(min_thickness 0.25)
			(keepout
				(tracks not_allowed)
				(vias allowed)
				(pads allowed)
				(copperpour not_allowed)
				(footprints allowed)
			)
			(placement
				(enabled no)
				(sheetname "")
			)
			(fill
				(thermal_gap 0.5)
				(thermal_bridge_width 0.5)
				(island_removal_mode 0)
			)
			(polygon
				(pts
					(xy 415.454846 -45.285152) (xy 415.962846 -45.285152) (xy 415.962846 -44.904152) (xy 415.454846 -44.904152)
				)
			)
		)
		(zone
			(layer "B.Cu")
			(hatch none 0.5)
			(connect_pads
				(clearance 0)
			)
			(min_thickness 0.25)
			(keepout
				(tracks allowed)
				(vias not_allowed)
				(pads allowed)
				(copperpour not_allowed)
				(footprints allowed)
			)
			(placement
				(enabled no)
				(sheetname "")
			)
			(fill
				(thermal_gap 0.5)
				(thermal_bridge_width 0.5)
				(island_removal_mode 0)
			)
			(polygon
				(pts
					(xy 415.454846 -44.904152) (xy 415.962846 -44.904152) (xy 415.962846 -45.285152) (xy 415.454846 -45.285152)
				)
			)
		)
	)
	(footprint ""
		(layer "B.Cu")
		(at 402.805646 -27.124152)
		(property "Reference" "R1U33"
			(at 0 0 0)
			(layer "B.SilkS")
			(hide yes)
			(effects
				(font
					(size 1.27 1.27)
				)
				(justify mirror)
			)
		)
		(property "Value" "*"
			(at -0.064008 -4.108196 0)
			(unlocked yes)
			(layer "B.Fab")
			(hide yes)
			(effects
				(font
					(size 1.27 1.016)
					(thickness 0.1524)
				)
				(justify mirror)
			)
		)
		(property "Device Type" "649R2F-GP_RCL_GP-649R2F-GP,64.A"
			(at -0.064008 -5.632196 0)
			(unlocked yes)
			(layer "B.Fab")
			(hide yes)
			(effects
				(font
					(size 1.27 1.016)
					(thickness 0.1524)
				)
				(justify mirror)
			)
		)
		(duplicate_pad_numbers_are_jumpers no)
		(fp_line
			(start -0.508 -0.9398)
			(end 0.508 -0.9398)
			(stroke
				(width 0.1524)
				(type default)
			)
			(layer "B.SilkS")
		)
		(fp_line
			(start 0.508 -0.9398)
			(end 0.508 0.9398)
			(stroke
				(width 0.1524)
				(type default)
			)
			(layer "B.SilkS")
		)
		(fp_rect
			(start 0.508 0.9398)
			(end -0.508 -0.9398)
			(stroke
				(width 0)
				(type default)
			)
			(fill no)
			(layer "B.CrtYd")
		)
		(fp_rect
			(start 0.508 0.9398)
			(end -0.508 -0.9398)
			(stroke
				(width 0)
				(type default)
			)
			(fill no)
			(layer "B.Fab")
		)
		(pad "1" smd custom
			(at 0 -0.4445 180)
			(size 0.1397 0.1397)
			(layers "B.Cu" "B.Mask" "B.Paste")
			(net "A_P12V_STBY_SCALED")
			(options
				(clearance outline)
				(anchor circle)
			)
			(primitives
				(gr_poly
					(pts
						(arc
							(start -0.1778 0.2794)
							(mid -0.249642 0.249642)
							(end -0.2794 0.1778)
						)
						(arc
							(start -0.2794 -0.1778)
							(mid -0.249642 -0.249642)
							(end -0.1778 -0.2794)
						)
						(arc
							(start 0.1778 -0.2794)
							(mid 0.249642 -0.249642)
							(end 0.2794 -0.1778)
						)
						(arc
							(start 0.2794 0.1778)
							(mid 0.249642 0.249642)
							(end 0.1778 0.2794)
						)
					)
					(width 0)
					(fill yes)
				)
			)
		)
		(pad "2" smd custom
			(at 0 0.4445 180)
			(size 0.1397 0.1397)
			(layers "B.Cu" "B.Mask" "B.Paste")
			(net "GND")
			(options
				(clearance outline)
				(anchor circle)
			)
			(primitives
				(gr_poly
					(pts
						(arc
							(start -0.1778 0.2794)
							(mid -0.249642 0.249642)
							(end -0.2794 0.1778)
						)
						(arc
							(start -0.2794 -0.1778)
							(mid -0.249642 -0.249642)
							(end -0.1778 -0.2794)
						)
						(arc
							(start 0.1778 -0.2794)
							(mid 0.249642 -0.249642)
							(end 0.2794 -0.1778)
						)
						(arc
							(start 0.2794 0.1778)
							(mid 0.249642 0.249642)
							(end 0.1778 0.2794)
						)
					)
					(width 0)
					(fill yes)
				)
			)
		)
	)
)
